# S9S_MB_2U (Grand Teton) — schematic netlist excerpt (pin names and nets, part order shuffled) for the footprints in the layout excerpt that follows; sources: Cadence DE-HDL packaged netlist, KiCad conversion of 03242023_DA0F0TMBIJ0_F0T_Motherboard_J_brd_V01_OCP.brd

PU203  MAX15090BEWIT  MAX15090BEWI+T EMPTY  pkg BGA28_0-5_3-525X2-065  page 156
  ISENSE  = P12V_OCP_SENSE_1
  VCC  = P12V_OCP_VCC_1
  IN_A3  = P12V_AUX
  OUT_A4  = P12V_OCP_SFF
  IN_A5  = P12V_AUX
  GATE  = P12V_OCP_GATE_1
  CDLY  = GND
  CB  = P12V_OCP_CB_1
  GND_B2  = GND
  IN_B3  = P12V_AUX
  OUT_B4  = P12V_OCP_SFF
  IN_B5  = P12V_AUX
  OUT_B6  = P12V_OCP_SFF
  \en#\  = GND
  GND_C1  = GND
  GND_C2  = GND
  IN_C3  = P12V_AUX
  OUT_C4  = P12V_OCP_SFF
  IN_C5  = P12V_AUX
  OUT_C6  = P12V_OCP_SFF
  \fault#\  = P12V_OCP_FAULT_1
  REG  = P12V_OCP_REG_1
  UV  = P12V_OCP_UV_1
  OV  = P12V_OCP_OV_1
  OUT_D4  = P12V_OCP_SFF
  IN_D5  = P12V_AUX
  OUT_D6  = P12V_OCP_SFF
  PG  = P12V_OCP_PWRGD_1

(kicad_pcb
	(version 20260206)
	(generator "pcbnew")
	(generator_version "10.0")
	(general
		(thickness 1.6)
		(legacy_teardrops no)
	)
	(paper "A4")
	(title_block
		(title "03242023_DA0F0TMBIJ0_F0T_Motherboard_J_brd_V01_OCP.brd")
		(comment 1 "Grand Teton / footprints 912-912 of 6105")
	)
	(layers
		(0 "F.Cu" signal "TOP")
		(4 "In1.Cu" signal "GND")
		(6 "In2.Cu" signal "IN1")
		(8 "In3.Cu" signal "GND1")
		(10 "In4.Cu" signal "IN2")
		(12 "In5.Cu" signal "GND2")
		(14 "In6.Cu" signal "IN3")
		(16 "In7.Cu" signal "GND3")
		(18 "In8.Cu" signal "VCC")
		(20 "In9.Cu" signal "VCC1")
		(22 "In10.Cu" signal "GND4")
		(24 "In11.Cu" signal "IN4")
		(26 "In12.Cu" signal "GND5")
		(28 "In13.Cu" signal "IN5")
		(30 "In14.Cu" signal "GND6")
		(32 "In15.Cu" signal "IN6")
		(34 "In16.Cu" signal "GND7")
		(2 "B.Cu" signal "BOTTOM")
		(9 "F.Adhes" user "F.Adhesive")
		(11 "B.Adhes" user "B.Adhesive")
		(13 "F.Paste" user "Package Geometry/Pastemask Top")
		(15 "B.Paste" user "Package Geometry/Pastemask Bottom")
		(5 "F.SilkS" user "Ref Des/Silkscreen Top")
		(7 "B.SilkS" user "Ref Des/Silkscreen Bottom")
		(1 "F.Mask" user "Board Geometry/Soldermask Top")
		(3 "B.Mask" user "Board Geometry/Soldermask Bottom")
		(17 "Dwgs.User" user "User.Drawings")
		(19 "Cmts.User" user "User.Comments")
		(21 "Eco1.User" user "User.Eco1")
		(23 "Eco2.User" user "User.Eco2")
		(25 "Edge.Cuts" user "Board Geometry/Outline")
		(27 "Margin" user)
		(31 "F.CrtYd" user "Package Geometry/Place Bound Top")
		(29 "B.CrtYd" user "Package Geometry/Place Bound Bottom")
		(35 "F.Fab" user "Ref Des/Assembly Top")
		(33 "B.Fab" user "Ref Des/Assembly Bottom")
	)
	(footprint ""
		(layer "F.Cu")
		(at 451.497192 -20.979638)
		(property "Reference" "PU203"
			(at 1.984248 -5.8674 0)
			(unlocked yes)
			(layer "F.SilkS")
			(effects
				(font
					(size 0.7874 0.5842)
					(thickness 0.1524)
				)
				(justify left)
			)
		)
		(property "Value" ""
			(at 0 0 0)
			(layer "F.Fab")
			(effects
				(font
					(size 1.27 1.27)
				)
			)
		)
		(duplicate_pad_numbers_are_jumpers no)
		(fp_line
			(start -1.774952 -1.039876)
			(end -1.774952 1.039876)
			(stroke
				(width 0.1524)
				(type default)
			)
			(layer "F.SilkS")
		)
		(fp_line
			(start -1.774952 1.039876)
			(end 1.774952 1.039876)
			(stroke
				(width 0.1524)
				(type default)
			)
			(layer "F.SilkS")
		)
		(fp_line
			(start 1.774952 -1.039876)
			(end -1.774952 -1.039876)
			(stroke
				(width 0.1524)
				(type default)
			)
			(layer "F.SilkS")
		)
		(fp_line
			(start 1.774952 1.039876)
			(end 1.774952 -1.039876)
			(stroke
				(width 0.1524)
				(type default)
			)
			(layer "F.SilkS")
		)
		(fp_poly
			(pts
				(xy -1.769872 -1.039876) (xy -1.769872 -0.249936) (xy -2.531872 -0.249936) (xy -2.531872 -1.801876)
				(xy -0.999998 -1.801876) (xy -0.999998 -1.039876)
			)
			(stroke
				(width 0)
				(type default)
			)
			(fill yes)
			(layer "F.SilkS")
		)
		(fp_line
			(start -1.769872 -1.039876)
			(end -1.769872 1.039876)
			(stroke
				(width 0.1)
				(type default)
			)
			(layer "F.Fab")
		)
		(fp_line
			(start -1.769872 1.039876)
			(end 1.769872 1.039876)
			(stroke
				(width 0.1)
				(type default)
			)
			(layer "F.Fab")
		)
		(fp_line
			(start 1.769872 -1.039876)
			(end -1.769872 -1.039876)
			(stroke
				(width 0.1)
				(type default)
			)
			(layer "F.Fab")
		)
		(fp_line
			(start 1.769872 1.039876)
			(end 1.769872 -1.039876)
			(stroke
				(width 0.1)
				(type default)
			)
			(layer "F.Fab")
		)
		(fp_poly
			(pts
				(xy -1.769872 -1.039876) (xy -0.999998 -1.039876) (xy -0.999998 -1.801876) (xy -2.531872 -1.801876)
				(xy -2.531872 -0.249936) (xy -1.769872 -0.249936)
			)
			(stroke
				(width 0)
				(type default)
			)
			(fill yes)
			(layer "F.Fab")
		)
		(pad "A1" smd circle
			(at -1.500124 -0.750062)
			(size 0.2286 0.2286)
			(layers "F.Cu" "F.Mask" "F.Paste")
			(net "P12V_OCP_SENSE_1")
		)
		(pad "A2" smd circle
			(at -0.999998 -0.750062)
			(size 0.2286 0.2286)
			(layers "F.Cu" "F.Mask" "F.Paste")
			(net "P12V_OCP_VCC_1")
		)
		(pad "A3" smd circle
			(at -0.499872 -0.750062)
			(size 0.2286 0.2286)
			(layers "F.Cu" "F.Mask" "F.Paste")
			(net "P12V_AUX")
		)
		(pad "A4" smd circle
			(at 0 -0.750062)
			(size 0.2286 0.2286)
			(layers "F.Cu" "F.Mask" "F.Paste")
			(net "P12V_OCP_SFF")
		)
		(pad "A5" smd circle
			(at 0.499872 -0.750062)
			(size 0.2286 0.2286)
			(layers "F.Cu" "F.Mask" "F.Paste")
			(net "P12V_AUX")
		)
		(pad "A6" smd circle
			(at 0.999998 -0.750062)
			(size 0.2286 0.2286)
			(layers "F.Cu" "F.Mask" "F.Paste")
			(net "P12V_OCP_GATE_1")
		)
		(pad "A7" smd circle
			(at 1.500124 -0.750062)
			(size 0.2286 0.2286)
			(layers "F.Cu" "F.Mask" "F.Paste")
			(net "GND")
		)
		(pad "B1" smd circle
			(at -1.500124 -0.249936)
			(size 0.2286 0.2286)
			(layers "F.Cu" "F.Mask" "F.Paste")
			(net "P12V_OCP_CB_1")
		)
		(pad "B2" smd circle
			(at -0.999998 -0.249936)
			(size 0.2286 0.2286)
			(layers "F.Cu" "F.Mask" "F.Paste")
			(net "GND")
		)
		(pad "B3" smd circle
			(at -0.499872 -0.249936)
			(size 0.2286 0.2286)
			(layers "F.Cu" "F.Mask" "F.Paste")
			(net "P12V_AUX")
		)
		(pad "B4" smd circle
			(at 0 -0.249936)
			(size 0.2286 0.2286)
			(layers "F.Cu" "F.Mask" "F.Paste")
			(net "P12V_OCP_SFF")
		)
		(pad "B5" smd circle
			(at 0.499872 -0.249936)
			(size 0.2286 0.2286)
			(layers "F.Cu" "F.Mask" "F.Paste")
			(net "P12V_AUX")
		)
		(pad "B6" smd circle
			(at 0.999998 -0.249936)
			(size 0.2286 0.2286)
			(layers "F.Cu" "F.Mask" "F.Paste")
			(net "P12V_OCP_SFF")
		)
		(pad "B7" smd circle
			(at 1.500124 -0.249936)
			(size 0.2286 0.2286)
			(layers "F.Cu" "F.Mask" "F.Paste")
			(net "GND")
		)
		(pad "C1" smd circle
			(at -1.500124 0.249936)
			(size 0.2286 0.2286)
			(layers "F.Cu" "F.Mask" "F.Paste")
			(net "GND")
		)
		(pad "C2" smd circle
			(at -0.999998 0.249936)
			(size 0.2286 0.2286)
			(layers "F.Cu" "F.Mask" "F.Paste")
			(net "GND")
		)
		(pad "C3" smd circle
			(at -0.499872 0.249936)
			(size 0.2286 0.2286)
			(layers "F.Cu" "F.Mask" "F.Paste")
			(net "P12V_AUX")
		)
		(pad "C4" smd circle
			(at 0 0.249936)
			(size 0.2286 0.2286)
			(layers "F.Cu" "F.Mask" "F.Paste")
			(net "P12V_OCP_SFF")
		)
		(pad "C5" smd circle
			(at 0.499872 0.249936)
			(size 0.2286 0.2286)
			(layers "F.Cu" "F.Mask" "F.Paste")
			(net "P12V_AUX")
		)
		(pad "C6" smd circle
			(at 0.999998 0.249936)
			(size 0.2286 0.2286)
			(layers "F.Cu" "F.Mask" "F.Paste")
			(net "P12V_OCP_SFF")
		)
		(pad "C7" smd circle
			(at 1.500124 0.249936)
			(size 0.2286 0.2286)
			(layers "F.Cu" "F.Mask" "F.Paste")
			(net "P12V_OCP_FAULT_1")
		)
		(pad "D1" smd circle
			(at -1.500124 0.750062)
			(size 0.2286 0.2286)
			(layers "F.Cu" "F.Mask" "F.Paste")
			(net "P12V_OCP_REG_1")
		)
		(pad "D2" smd circle
			(at -0.999998 0.750062)
			(size 0.2286 0.2286)
			(layers "F.Cu" "F.Mask" "F.Paste")
			(net "P12V_OCP_UV_1")
		)
		(pad "D3" smd circle
			(at -0.499872 0.750062)
			(size 0.2286 0.2286)
			(layers "F.Cu" "F.Mask" "F.Paste")
			(net "P12V_OCP_OV_1")
		)
		(pad "D4" smd circle
			(at 0 0.750062)
			(size 0.2286 0.2286)
			(layers "F.Cu" "F.Mask" "F.Paste")
			(net "P12V_OCP_SFF")
		)
		(pad "D5" smd circle
			(at 0.499872 0.750062)
			(size 0.2286 0.2286)
			(layers "F.Cu" "F.Mask" "F.Paste")
			(net "P12V_AUX")
		)
		(pad "D6" smd circle
			(at 0.999998 0.750062)
			(size 0.2286 0.2286)
			(layers "F.Cu" "F.Mask" "F.Paste")
			(net "P12V_OCP_SFF")
		)
		(pad "D7" smd circle
			(at 1.500124 0.750062)
			(size 0.2286 0.2286)
			(layers "F.Cu" "F.Mask" "F.Paste")
			(net "P12V_OCP_PWRGD_1")
		)
	)
)
